# BASEBOARD_FAB2 (Tioga Pass) — schematic netlist excerpt (pin names and nets, part order shuffled) for the footprints in the layout excerpt that follows; sources: Cadence DE-HDL packaged netlist, KiCad conversion of Wiwynn_Tioga_Pass_MB.brd

C2D22  CAP_A  22.0UF 4V 20% X6S  pkg 0603V  page 76 : A = PVCCIN_CPU1 ; B = GND
R8C9  RES  4.75K 1% CHIP  pkg 0402  page 126 : A = P3V3_STBY ; B = IRQ_SML0_ALERT_N
R8E7  RES  22.1 1.0% CHIP  pkg 0402  page 196 : A = PWRGD_P12V_HSC_DLY_R ; B = PWRGD_P12V_HSC_DLY

(kicad_pcb
	(version 20260206)
	(generator "pcbnew")
	(generator_version "10.0")
	(general
		(thickness 1.6)
		(legacy_teardrops no)
	)
	(paper "A4")
	(title_block
		(title "Wiwynn_Tioga_Pass_MB.brd")
		(comment 1 "Tioga Pass / footprints 1513-1515 of 4770")
	)
	(layers
		(0 "F.Cu" signal "TOP")
		(4 "In1.Cu" signal "L2GND")
		(6 "In2.Cu" signal "L3")
		(8 "In3.Cu" signal "L4GND")
		(10 "In4.Cu" signal "L5")
		(12 "In5.Cu" signal "L6GND")
		(14 "In6.Cu" signal "L7VCC")
		(16 "In7.Cu" signal "L8VCC")
		(18 "In8.Cu" signal "L9GND")
		(20 "In9.Cu" signal "L10")
		(22 "In10.Cu" signal "L11GND")
		(24 "In11.Cu" signal "L12")
		(26 "In12.Cu" signal "L13GND")
		(2 "B.Cu" signal "BOTTOM")
		(9 "F.Adhes" user "F.Adhesive")
		(11 "B.Adhes" user "B.Adhesive")
		(13 "F.Paste" user "Package Geometry/Pastemask Top")
		(15 "B.Paste" user "Package Geometry/Pastemask Bottom")
		(5 "F.SilkS" user "Ref Des/Silkscreen Top")
		(7 "B.SilkS" user "Ref Des/Silkscreen Bottom")
		(1 "F.Mask" user "Board Geometry/Soldermask Top")
		(3 "B.Mask" user "Board Geometry/Soldermask Bottom")
		(17 "Dwgs.User" user "User.Drawings")
		(19 "Cmts.User" user "User.Comments")
		(21 "Eco1.User" user "User.Eco1")
		(23 "Eco2.User" user "User.Eco2")
		(25 "Edge.Cuts" user "Board Geometry/Outline")
		(27 "Margin" user)
		(31 "F.CrtYd" user "Package Geometry/Place Bound Top")
		(29 "B.CrtYd" user "Package Geometry/Place Bound Bottom")
		(35 "F.Fab" user "Ref Des/Assembly Top")
		(33 "B.Fab" user "Ref Des/Assembly Bottom")
	)
	(footprint ""
		(layer "F.Cu")
		(at 398.145 -77.7875 180)
		(property "Reference" "R8E7"
			(at 0 0 180)
			(layer "F.SilkS")
			(hide yes)
			(effects
				(font
					(size 1.27 1.27)
				)
			)
		)
		(property "Value" ""
			(at 0 0 180)
			(layer "F.Fab")
			(effects
				(font
					(size 1.27 1.27)
				)
			)
		)
		(duplicate_pad_numbers_are_jumpers no)
		(fp_poly
			(pts
				(xy -0.2794 -0.1016) (xy 0.2794 -0.1016) (xy 0.2794 0.9906) (xy -0.2794 0.9906)
			)
			(stroke
				(width 0)
				(type default)
			)
			(fill no)
			(layer "F.CrtYd")
		)
		(fp_line
			(start 0.2794 0.9906)
			(end 0.2794 -0.1016)
			(stroke
				(width 0.1)
				(type default)
			)
			(layer "F.Fab")
		)
		(fp_line
			(start 0.2794 -0.1016)
			(end -0.2794 -0.1016)
			(stroke
				(width 0.1)
				(type default)
			)
			(layer "F.Fab")
		)
		(fp_line
			(start -0.2794 0.9906)
			(end 0.2794 0.9906)
			(stroke
				(width 0.1)
				(type default)
			)
			(layer "F.Fab")
		)
		(fp_line
			(start -0.2794 -0.1016)
			(end -0.2794 0.9906)
			(stroke
				(width 0.1)
				(type default)
			)
			(layer "F.Fab")
		)
		(pad "1" smd rect
			(at 0 0 180)
			(size 0.508 0.508)
			(layers "F.Cu" "F.Mask" "F.Paste")
			(net "PWRGD_P12V_HSC_DLY_R")
		)
		(pad "2" smd rect
			(at 0 0.889 180)
			(size 0.508 0.508)
			(layers "F.Cu" "F.Mask" "F.Paste")
			(net "PWRGD_P12V_HSC_DLY")
		)
		(zone
			(layer "F.Cu")
			(hatch none 0.5)
			(connect_pads
				(clearance 0)
			)
			(min_thickness 0.25)
			(keepout
				(tracks not_allowed)
				(vias allowed)
				(pads allowed)
				(copperpour not_allowed)
				(footprints allowed)
			)
			(placement
				(enabled no)
				(sheetname "")
			)
			(fill
				(thermal_gap 0.5)
				(thermal_bridge_width 0.5)
				(island_removal_mode 0)
			)
			(polygon
				(pts
					(xy 398.399 -78.4225) (xy 397.891 -78.4225) (xy 397.891 -78.0415) (xy 398.399 -78.0415)
				)
			)
		)
		(zone
			(layer "F.Cu")
			(hatch none 0.5)
			(connect_pads
				(clearance 0)
			)
			(min_thickness 0.25)
			(keepout
				(tracks allowed)
				(vias not_allowed)
				(pads allowed)
				(copperpour not_allowed)
				(footprints allowed)
			)
			(placement
				(enabled no)
				(sheetname "")
			)
			(fill
				(thermal_gap 0.5)
				(thermal_bridge_width 0.5)
				(island_removal_mode 0)
			)
			(polygon
				(pts
					(xy 398.399 -78.0415) (xy 397.891 -78.0415) (xy 397.891 -78.4225) (xy 398.399 -78.4225)
				)
			)
		)
	)
	(footprint ""
		(layer "F.Cu")
		(at 411.0355 -110.617 -90)
		(property "Reference" "R8C9"
			(at 0 0 270)
			(layer "F.SilkS")
			(hide yes)
			(effects
				(font
					(size 1.27 1.27)
				)
			)
		)
		(property "Value" ""
			(at 0 0 270)
			(layer "F.Fab")
			(effects
				(font
					(size 1.27 1.27)
				)
			)
		)
		(duplicate_pad_numbers_are_jumpers no)
		(fp_poly
			(pts
				(xy -0.2794 -0.1016) (xy 0.2794 -0.1016) (xy 0.2794 0.9906) (xy -0.2794 0.9906)
			)
			(stroke
				(width 0)
				(type default)
			)
			(fill no)
			(layer "F.CrtYd")
		)
		(fp_line
			(start -0.2794 0.9906)
			(end 0.2794 0.9906)
			(stroke
				(width 0.1)
				(type default)
			)
			(layer "F.Fab")
		)
		(fp_line
			(start 0.2794 0.9906)
			(end 0.2794 -0.1016)
			(stroke
				(width 0.1)
				(type default)
			)
			(layer "F.Fab")
		)
		(fp_line
			(start -0.2794 -0.1016)
			(end -0.2794 0.9906)
			(stroke
				(width 0.1)
				(type default)
			)
			(layer "F.Fab")
		)
		(fp_line
			(start 0.2794 -0.1016)
			(end -0.2794 -0.1016)
			(stroke
				(width 0.1)
				(type default)
			)
			(layer "F.Fab")
		)
		(pad "1" smd rect
			(at 0 0 270)
			(size 0.508 0.508)
			(layers "F.Cu" "F.Mask" "F.Paste")
			(net "P3V3_STBY")
		)
		(pad "2" smd rect
			(at 0 0.889 270)
			(size 0.508 0.508)
			(layers "F.Cu" "F.Mask" "F.Paste")
			(net "IRQ_SML0_ALERT_N")
		)
		(zone
			(layer "F.Cu")
			(hatch none 0.5)
			(connect_pads
				(clearance 0)
			)
			(min_thickness 0.25)
			(keepout
				(tracks not_allowed)
				(vias allowed)
				(pads allowed)
				(copperpour not_allowed)
				(footprints allowed)
			)
			(placement
				(enabled no)
				(sheetname "")
			)
			(fill
				(thermal_gap 0.5)
				(thermal_bridge_width 0.5)
				(island_removal_mode 0)
			)
			(polygon
				(pts
					(xy 410.4005 -110.871) (xy 410.4005 -110.363) (xy 410.7815 -110.363) (xy 410.7815 -110.871)
				)
			)
		)
		(zone
			(layer "F.Cu")
			(hatch none 0.5)
			(connect_pads
				(clearance 0)
			)
			(min_thickness 0.25)
			(keepout
				(tracks allowed)
				(vias not_allowed)
				(pads allowed)
				(copperpour not_allowed)
				(footprints allowed)
			)
			(placement
				(enabled no)
				(sheetname "")
			)
			(fill
				(thermal_gap 0.5)
				(thermal_bridge_width 0.5)
				(island_removal_mode 0)
			)
			(polygon
				(pts
					(xy 410.7815 -110.871) (xy 410.7815 -110.363) (xy 410.4005 -110.363) (xy 410.4005 -110.871)
				)
			)
		)
	)
	(footprint ""
		(layer "F.Cu")
		(at 96.94164 -77.636116)
		(property "Reference" "C2D22"
			(at 0 0 0)
			(layer "F.SilkS")
			(hide yes)
			(effects
				(font
					(size 1.27 1.27)
				)
			)
		)
		(property "Value" ""
			(at 0 0 0)
			(layer "F.Fab")
			(effects
				(font
					(size 1.27 1.27)
				)
			)
		)
		(duplicate_pad_numbers_are_jumpers no)
		(fp_poly
			(pts
				(xy -0.4953 -0.2032) (xy 0.4953 -0.2032) (xy 0.4953 1.6002) (xy -0.4953 1.6002)
			)
			(stroke
				(width 0)
				(type default)
			)
			(fill no)
			(layer "F.CrtYd")
		)
		(fp_line
			(start -0.4953 -0.2032)
			(end 0.4953 -0.2032)
			(stroke
				(width 0.1)
				(type default)
			)
			(layer "F.Fab")
		)
		(fp_line
			(start -0.4953 1.6002)
			(end -0.4953 -0.2032)
			(stroke
				(width 0.1)
				(type default)
			)
			(layer "F.Fab")
		)
		(fp_line
			(start 0.4953 -0.2032)
			(end 0.4953 1.6002)
			(stroke
				(width 0.1)
				(type default)
			)
			(layer "F.Fab")
		)
		(fp_line
			(start 0.4953 1.6002)
			(end -0.4953 1.6002)
			(stroke
				(width 0.1)
				(type default)
			)
			(layer "F.Fab")
		)
		(pad "1" smd rect
			(at 0 0)
			(size 0.762 0.889)
			(layers "F.Cu" "F.Mask" "F.Paste")
			(net "PVCCIN_CPU1")
		)
		(pad "2" smd rect
			(at 0 1.397)
			(size 0.762 0.889)
			(layers "F.Cu" "F.Mask" "F.Paste")
			(net "GND")
		)
		(zone
			(layer "F.Cu")
			(hatch none 0.5)
			(connect_pads
				(clearance 0)
			)
			(min_thickness 0.25)
			(keepout
				(tracks not_allowed)
				(vias allowed)
				(pads allowed)
				(copperpour not_allowed)
				(footprints allowed)
			)
			(placement
				(enabled no)
				(sheetname "")
			)
			(fill
				(thermal_gap 0.5)
				(thermal_bridge_width 0.5)
				(island_removal_mode 0)
			)
			(polygon
				(pts
					(xy 96.56064 -77.191616) (xy 97.32264 -77.191616) (xy 97.32264 -76.683616) (xy 96.56064 -76.683616)
				)
			)
		)
	)
)
